(kicad_pcb
	(version 20260206)
	(generator "pcbnew")
	(generator_version "10.0")
	(general
		(thickness 1.6)
		(legacy_teardrops no)
	)
	(paper "A4")
	(title_block
		(title "03242023_DA0F0TMBIJ0_F0T_Motherboard_J_brd_V01_OCP.brd")
		(comment 1 "Grand Teton / footprints 3078-3083 of 6105")
	)
	(layers
		(0 "F.Cu" signal "TOP")
		(4 "In1.Cu" signal "GND")
		(6 "In2.Cu" signal "IN1")
		(8 "In3.Cu" signal "GND1")
		(10 "In4.Cu" signal "IN2")
		(12 "In5.Cu" signal "GND2")
		(14 "In6.Cu" signal "IN3")
		(16 "In7.Cu" signal "GND3")
		(18 "In8.Cu" signal "VCC")
		(20 "In9.Cu" signal "VCC1")
		(22 "In10.Cu" signal "GND4")
		(24 "In11.Cu" signal "IN4")
		(26 "In12.Cu" signal "GND5")
		(28 "In13.Cu" signal "IN5")
		(30 "In14.Cu" signal "GND6")
		(32 "In15.Cu" signal "IN6")
		(34 "In16.Cu" signal "GND7")
		(2 "B.Cu" signal "BOTTOM")
		(9 "F.Adhes" user "F.Adhesive")
		(11 "B.Adhes" user "B.Adhesive")
		(13 "F.Paste" user "Package Geometry/Pastemask Top")
		(15 "B.Paste" user "Package Geometry/Pastemask Bottom")
		(5 "F.SilkS" user "Ref Des/Silkscreen Top")
		(7 "B.SilkS" user "Ref Des/Silkscreen Bottom")
		(1 "F.Mask" user "Board Geometry/Soldermask Top")
		(3 "B.Mask" user "Board Geometry/Soldermask Bottom")
		(17 "Dwgs.User" user "User.Drawings")
		(19 "Cmts.User" user "User.Comments")
		(21 "Eco1.User" user "User.Eco1")
		(23 "Eco2.User" user "User.Eco2")
		(25 "Edge.Cuts" user "Board Geometry/Outline")
		(27 "Margin" user)
		(31 "F.CrtYd" user "Package Geometry/Place Bound Top")
		(29 "B.CrtYd" user "Package Geometry/Place Bound Bottom")
		(35 "F.Fab" user "Ref Des/Assembly Top")
		(33 "B.Fab" user "Ref Des/Assembly Bottom")
	)
	(footprint ""
		(layer "F.Cu")
		(at 447.557652 -18.449798)
		(property "Reference" "PR3786"
			(at 0 0 0)
			(layer "F.SilkS")
			(hide yes)
			(effects
				(font
					(size 1.27 1.27)
				)
			)
		)
		(property "Value" ""
			(at 0 0 0)
			(layer "F.Fab")
			(effects
				(font
					(size 1.27 1.27)
				)
			)
		)
		(duplicate_pad_numbers_are_jumpers no)
		(fp_line
			(start -0.7874 -0.4064)
			(end 0.7874 -0.4064)
			(stroke
				(width 0.1524)
				(type default)
			)
			(layer "F.SilkS")
		)
		(fp_line
			(start -0.7874 0.4064)
			(end -0.7874 -0.4064)
			(stroke
				(width 0.1524)
				(type default)
			)
			(layer "F.SilkS")
		)
		(fp_line
			(start 0.7874 -0.4064)
			(end 0.7874 0.4064)
			(stroke
				(width 0.1524)
				(type default)
			)
			(layer "F.SilkS")
		)
		(fp_line
			(start 0.7874 0.4064)
			(end -0.7874 0.4064)
			(stroke
				(width 0.1524)
				(type default)
			)
			(layer "F.SilkS")
		)
		(fp_line
			(start -0.67945 -0.305054)
			(end -0.12065 -0.305054)
			(stroke
				(width 0.1)
				(type default)
			)
			(layer "F.Fab")
		)
		(fp_line
			(start -0.67945 0.3048)
			(end -0.67945 -0.305054)
			(stroke
				(width 0.1)
				(type default)
			)
			(layer "F.Fab")
		)
		(fp_line
			(start -0.12065 -0.305054)
			(end -0.12065 -0.2794)
			(stroke
				(width 0.1)
				(type default)
			)
			(layer "F.Fab")
		)
		(fp_line
			(start -0.12065 -0.2794)
			(end 0.12065 -0.2794)
			(stroke
				(width 0.1)
				(type default)
			)
			(layer "F.Fab")
		)
		(fp_line
			(start -0.12065 0.2794)
			(end -0.12065 0.3048)
			(stroke
				(width 0.1)
				(type default)
			)
			(layer "F.Fab")
		)
		(fp_line
			(start -0.12065 0.3048)
			(end -0.67945 0.3048)
			(stroke
				(width 0.1)
				(type default)
			)
			(layer "F.Fab")
		)
		(fp_line
			(start 0.120396 0.2794)
			(end -0.12065 0.2794)
			(stroke
				(width 0.1)
				(type default)
			)
			(layer "F.Fab")
		)
		(fp_line
			(start 0.120396 0.3048)
			(end 0.120396 0.2794)
			(stroke
				(width 0.1)
				(type default)
			)
			(layer "F.Fab")
		)
		(fp_line
			(start 0.12065 -0.3048)
			(end 0.67945 -0.3048)
			(stroke
				(width 0.1)
				(type default)
			)
			(layer "F.Fab")
		)
		(fp_line
			(start 0.12065 -0.2794)
			(end 0.12065 -0.3048)
			(stroke
				(width 0.1)
				(type default)
			)
			(layer "F.Fab")
		)
		(fp_line
			(start 0.67945 -0.3048)
			(end 0.67945 0.3048)
			(stroke
				(width 0.1)
				(type default)
			)
			(layer "F.Fab")
		)
		(fp_line
			(start 0.67945 0.3048)
			(end 0.120396 0.3048)
			(stroke
				(width 0.1)
				(type default)
			)
			(layer "F.Fab")
		)
		(pad "1" smd circle
			(at -0.40005 0)
			(size 0 0)
			(layers "F.Cu" "F.Mask" "F.Paste")
			(net "P12V_AUX")
		)
		(pad "2" smd circle
			(at 0.40005 0)
			(size 0 0)
			(layers "F.Cu" "F.Mask" "F.Paste")
			(net "P12V_OCP_UV_1")
		)
	)
	(footprint ""
		(layer "F.Cu")
		(at 89.596468 -341.729822 90)
		(property "Reference" "PR1790"
			(at 0 0 90)
			(layer "F.SilkS")
			(hide yes)
			(effects
				(font
					(size 1.27 1.27)
				)
			)
		)
		(property "Value" ""
			(at 0 0 90)
			(layer "F.Fab")
			(effects
				(font
					(size 1.27 1.27)
				)
			)
		)
		(duplicate_pad_numbers_are_jumpers no)
		(fp_line
			(start 0.7874 -0.4064)
			(end 0.7874 0.4064)
			(stroke
				(width 0.1524)
				(type default)
			)
			(layer "F.SilkS")
		)
		(fp_line
			(start -0.7874 -0.4064)
			(end 0.7874 -0.4064)
			(stroke
				(width 0.1524)
				(type default)
			)
			(layer "F.SilkS")
		)
		(fp_line
			(start 0.7874 0.4064)
			(end -0.7874 0.4064)
			(stroke
				(width 0.1524)
				(type default)
			)
			(layer "F.SilkS")
		)
		(fp_line
			(start -0.7874 0.4064)
			(end -0.7874 -0.4064)
			(stroke
				(width 0.1524)
				(type default)
			)
			(layer "F.SilkS")
		)
		(fp_line
			(start -0.12065 -0.305054)
			(end -0.12065 -0.2794)
			(stroke
				(width 0.1)
				(type default)
			)
			(layer "F.Fab")
		)
		(fp_line
			(start -0.67945 -0.305054)
			(end -0.12065 -0.305054)
			(stroke
				(width 0.1)
				(type default)
			)
			(layer "F.Fab")
		)
		(fp_line
			(start 0.67945 -0.3048)
			(end 0.67945 0.3048)
			(stroke
				(width 0.1)
				(type default)
			)
			(layer "F.Fab")
		)
		(fp_line
			(start 0.12065 -0.3048)
			(end 0.67945 -0.3048)
			(stroke
				(width 0.1)
				(type default)
			)
			(layer "F.Fab")
		)
		(fp_line
			(start 0.12065 -0.2794)
			(end 0.12065 -0.3048)
			(stroke
				(width 0.1)
				(type default)
			)
			(layer "F.Fab")
		)
		(fp_line
			(start -0.12065 -0.2794)
			(end 0.12065 -0.2794)
			(stroke
				(width 0.1)
				(type default)
			)
			(layer "F.Fab")
		)
		(fp_line
			(start 0.120396 0.2794)
			(end -0.12065 0.2794)
			(stroke
				(width 0.1)
				(type default)
			)
			(layer "F.Fab")
		)
		(fp_line
			(start -0.12065 0.2794)
			(end -0.12065 0.3048)
			(stroke
				(width 0.1)
				(type default)
			)
			(layer "F.Fab")
		)
		(fp_line
			(start 0.67945 0.3048)
			(end 0.120396 0.3048)
			(stroke
				(width 0.1)
				(type default)
			)
			(layer "F.Fab")
		)
		(fp_line
			(start 0.120396 0.3048)
			(end 0.120396 0.2794)
			(stroke
				(width 0.1)
				(type default)
			)
			(layer "F.Fab")
		)
		(fp_line
			(start -0.12065 0.3048)
			(end -0.67945 0.3048)
			(stroke
				(width 0.1)
				(type default)
			)
			(layer "F.Fab")
		)
		(fp_line
			(start -0.67945 0.3048)
			(end -0.67945 -0.305054)
			(stroke
				(width 0.1)
				(type default)
			)
			(layer "F.Fab")
		)
		(pad "1" smd circle
			(at -0.40005 0 90)
			(size 0 0)
			(layers "F.Cu" "F.Mask" "F.Paste")
			(net "SW_PVCCIN_CPU1_BOOT6")
		)
		(pad "2" smd circle
			(at 0.40005 0 90)
			(size 0 0)
			(layers "F.Cu" "F.Mask" "F.Paste")
			(net "SW_PVCCIN_CPU1_BOOT6_R")
		)
	)
	(footprint ""
		(layer "F.Cu")
		(at 197.180962 -39.046912)
		(property "Reference" "R1857"
			(at 0 0 0)
			(layer "F.SilkS")
			(hide yes)
			(effects
				(font
					(size 1.27 1.27)
				)
			)
		)
		(property "Value" ""
			(at 0 0 0)
			(layer "F.Fab")
			(effects
				(font
					(size 1.27 1.27)
				)
			)
		)
		(duplicate_pad_numbers_are_jumpers no)
		(fp_line
			(start -0.7874 -0.4064)
			(end 0.7874 -0.4064)
			(stroke
				(width 0.1524)
				(type default)
			)
			(layer "F.SilkS")
		)
		(fp_line
			(start -0.7874 0.4064)
			(end -0.7874 -0.4064)
			(stroke
				(width 0.1524)
				(type default)
			)
			(layer "F.SilkS")
		)
		(fp_line
			(start 0.7874 -0.4064)
			(end 0.7874 0.4064)
			(stroke
				(width 0.1524)
				(type default)
			)
			(layer "F.SilkS")
		)
		(fp_line
			(start 0.7874 0.4064)
			(end -0.7874 0.4064)
			(stroke
				(width 0.1524)
				(type default)
			)
			(layer "F.SilkS")
		)
		(fp_line
			(start -0.67945 -0.305054)
			(end -0.12065 -0.305054)
			(stroke
				(width 0.1)
				(type default)
			)
			(layer "F.Fab")
		)
		(fp_line
			(start -0.67945 0.3048)
			(end -0.67945 -0.305054)
			(stroke
				(width 0.1)
				(type default)
			)
			(layer "F.Fab")
		)
		(fp_line
			(start -0.12065 -0.305054)
			(end -0.12065 -0.2794)
			(stroke
				(width 0.1)
				(type default)
			)
			(layer "F.Fab")
		)
		(fp_line
			(start -0.12065 -0.2794)
			(end 0.12065 -0.2794)
			(stroke
				(width 0.1)
				(type default)
			)
			(layer "F.Fab")
		)
		(fp_line
			(start -0.12065 0.2794)
			(end -0.12065 0.3048)
			(stroke
				(width 0.1)
				(type default)
			)
			(layer "F.Fab")
		)
		(fp_line
			(start -0.12065 0.3048)
			(end -0.67945 0.3048)
			(stroke
				(width 0.1)
				(type default)
			)
			(layer "F.Fab")
		)
		(fp_line
			(start 0.120396 0.2794)
			(end -0.12065 0.2794)
			(stroke
				(width 0.1)
				(type default)
			)
			(layer "F.Fab")
		)
		(fp_line
			(start 0.120396 0.3048)
			(end 0.120396 0.2794)
			(stroke
				(width 0.1)
				(type default)
			)
			(layer "F.Fab")
		)
		(fp_line
			(start 0.12065 -0.3048)
			(end 0.67945 -0.3048)
			(stroke
				(width 0.1)
				(type default)
			)
			(layer "F.Fab")
		)
		(fp_line
			(start 0.12065 -0.2794)
			(end 0.12065 -0.3048)
			(stroke
				(width 0.1)
				(type default)
			)
			(layer "F.Fab")
		)
		(fp_line
			(start 0.67945 -0.3048)
			(end 0.67945 0.3048)
			(stroke
				(width 0.1)
				(type default)
			)
			(layer "F.Fab")
		)
		(fp_line
			(start 0.67945 0.3048)
			(end 0.120396 0.3048)
			(stroke
				(width 0.1)
				(type default)
			)
			(layer "F.Fab")
		)
		(pad "1" smd circle
			(at -0.40005 0)
			(size 0 0)
			(layers "F.Cu" "F.Mask" "F.Paste")
			(net "P3V3_AUX")
		)
		(pad "2" smd circle
			(at 0.40005 0)
			(size 0 0)
			(layers "F.Cu" "F.Mask" "F.Paste")
			(net "P12V_SCM_EN")
		)
	)
	(footprint ""
		(layer "F.Cu")
		(at 21.176996 -100.54971 180)
		(property "Reference" "R3656"
			(at 0 0 180)
			(layer "F.SilkS")
			(hide yes)
			(effects
				(font
					(size 1.27 1.27)
				)
			)
		)
		(property "Value" ""
			(at 0 0 180)
			(layer "F.Fab")
			(effects
				(font
					(size 1.27 1.27)
				)
			)
		)
		(duplicate_pad_numbers_are_jumpers no)
		(fp_line
			(start 0.7874 0.4064)
			(end -0.7874 0.4064)
			(stroke
				(width 0.1524)
				(type default)
			)
			(layer "F.SilkS")
		)
		(fp_line
			(start 0.7874 -0.4064)
			(end 0.7874 0.4064)
			(stroke
				(width 0.1524)
				(type default)
			)
			(layer "F.SilkS")
		)
		(fp_line
			(start -0.7874 0.4064)
			(end -0.7874 -0.4064)
			(stroke
				(width 0.1524)
				(type default)
			)
			(layer "F.SilkS")
		)
		(fp_line
			(start -0.7874 -0.4064)
			(end 0.7874 -0.4064)
			(stroke
				(width 0.1524)
				(type default)
			)
			(layer "F.SilkS")
		)
		(fp_line
			(start 0.67945 0.3048)
			(end 0.120396 0.3048)
			(stroke
				(width 0.1)
				(type default)
			)
			(layer "F.Fab")
		)
		(fp_line
			(start 0.67945 -0.3048)
			(end 0.67945 0.3048)
			(stroke
				(width 0.1)
				(type default)
			)
			(layer "F.Fab")
		)
		(fp_line
			(start 0.12065 -0.2794)
			(end 0.12065 -0.3048)
			(stroke
				(width 0.1)
				(type default)
			)
			(layer "F.Fab")
		)
		(fp_line
			(start 0.12065 -0.3048)
			(end 0.67945 -0.3048)
			(stroke
				(width 0.1)
				(type default)
			)
			(layer "F.Fab")
		)
		(fp_line
			(start 0.120396 0.3048)
			(end 0.120396 0.2794)
			(stroke
				(width 0.1)
				(type default)
			)
			(layer "F.Fab")
		)
		(fp_line
			(start 0.120396 0.2794)
			(end -0.12065 0.2794)
			(stroke
				(width 0.1)
				(type default)
			)
			(layer "F.Fab")
		)
		(fp_line
			(start -0.12065 0.3048)
			(end -0.67945 0.3048)
			(stroke
				(width 0.1)
				(type default)
			)
			(layer "F.Fab")
		)
		(fp_line
			(start -0.12065 0.2794)
			(end -0.12065 0.3048)
			(stroke
				(width 0.1)
				(type default)
			)
			(layer "F.Fab")
		)
		(fp_line
			(start -0.12065 -0.2794)
			(end 0.12065 -0.2794)
			(stroke
				(width 0.1)
				(type default)
			)
			(layer "F.Fab")
		)
		(fp_line
			(start -0.12065 -0.305054)
			(end -0.12065 -0.2794)
			(stroke
				(width 0.1)
				(type default)
			)
			(layer "F.Fab")
		)
		(fp_line
			(start -0.67945 0.3048)
			(end -0.67945 -0.305054)
			(stroke
				(width 0.1)
				(type default)
			)
			(layer "F.Fab")
		)
		(fp_line
			(start -0.67945 -0.305054)
			(end -0.12065 -0.305054)
			(stroke
				(width 0.1)
				(type default)
			)
			(layer "F.Fab")
		)
		(pad "1" smd circle
			(at -0.40005 0 180)
			(size 0 0)
			(layers "F.Cu" "F.Mask" "F.Paste")
			(net "P3V3_AUX")
		)
		(pad "2" smd circle
			(at 0.40005 0 180)
			(size 0 0)
			(layers "F.Cu" "F.Mask" "F.Paste")
			(net "USB_HUB_OVCUR1")
		)
	)
	(footprint ""
		(layer "F.Cu")
		(at 173.216062 -30.370272 180)
		(property "Reference" "PR4007"
			(at 0 0 180)
			(layer "F.SilkS")
			(hide yes)
			(effects
				(font
					(size 1.27 1.27)
				)
			)
		)
		(property "Value" ""
			(at 0 0 180)
			(layer "F.Fab")
			(effects
				(font
					(size 1.27 1.27)
				)
			)
		)
		(duplicate_pad_numbers_are_jumpers no)
		(fp_line
			(start 0.7874 0.4064)
			(end -0.7874 0.4064)
			(stroke
				(width 0.1524)
				(type default)
			)
			(layer "F.SilkS")
		)
		(fp_line
			(start 0.7874 -0.4064)
			(end 0.7874 0.4064)
			(stroke
				(width 0.1524)
				(type default)
			)
			(layer "F.SilkS")
		)
		(fp_line
			(start -0.7874 0.4064)
			(end -0.7874 -0.4064)
			(stroke
				(width 0.1524)
				(type default)
			)
			(layer "F.SilkS")
		)
		(fp_line
			(start -0.7874 -0.4064)
			(end 0.7874 -0.4064)
			(stroke
				(width 0.1524)
				(type default)
			)
			(layer "F.SilkS")
		)
		(fp_line
			(start 0.67945 0.3048)
			(end 0.120396 0.3048)
			(stroke
				(width 0.1)
				(type default)
			)
			(layer "F.Fab")
		)
		(fp_line
			(start 0.67945 -0.3048)
			(end 0.67945 0.3048)
			(stroke
				(width 0.1)
				(type default)
			)
			(layer "F.Fab")
		)
		(fp_line
			(start 0.12065 -0.2794)
			(end 0.12065 -0.3048)
			(stroke
				(width 0.1)
				(type default)
			)
			(layer "F.Fab")
		)
		(fp_line
			(start 0.12065 -0.3048)
			(end 0.67945 -0.3048)
			(stroke
				(width 0.1)
				(type default)
			)
			(layer "F.Fab")
		)
		(fp_line
			(start 0.120396 0.3048)
			(end 0.120396 0.2794)
			(stroke
				(width 0.1)
				(type default)
			)
			(layer "F.Fab")
		)
		(fp_line
			(start 0.120396 0.2794)
			(end -0.12065 0.2794)
			(stroke
				(width 0.1)
				(type default)
			)
			(layer "F.Fab")
		)
		(fp_line
			(start -0.12065 0.3048)
			(end -0.67945 0.3048)
			(stroke
				(width 0.1)
				(type default)
			)
			(layer "F.Fab")
		)
		(fp_line
			(start -0.12065 0.2794)
			(end -0.12065 0.3048)
			(stroke
				(width 0.1)
				(type default)
			)
			(layer "F.Fab")
		)
		(fp_line
			(start -0.12065 -0.2794)
			(end 0.12065 -0.2794)
			(stroke
				(width 0.1)
				(type default)
			)
			(layer "F.Fab")
		)
		(fp_line
			(start -0.12065 -0.305054)
			(end -0.12065 -0.2794)
			(stroke
				(width 0.1)
				(type default)
			)
			(layer "F.Fab")
		)
		(fp_line
			(start -0.67945 0.3048)
			(end -0.67945 -0.305054)
			(stroke
				(width 0.1)
				(type default)
			)
			(layer "F.Fab")
		)
		(fp_line
			(start -0.67945 -0.305054)
			(end -0.12065 -0.305054)
			(stroke
				(width 0.1)
				(type default)
			)
			(layer "F.Fab")
		)
		(pad "1" smd circle
			(at -0.40005 0 180)
			(size 0 0)
			(layers "F.Cu" "F.Mask" "F.Paste")
			(net "P12V_SCM_FLTB_N")
		)
		(pad "2" smd circle
			(at 0.40005 0 180)
			(size 0 0)
			(layers "F.Cu" "F.Mask" "F.Paste")
			(net "P3V3_AUX")
		)
	)
	(footprint ""
		(layer "F.Cu")
		(at 420.4716 -169.088562 180)
		(property "Reference" "PC193"
			(at 0 0 180)
			(layer "F.SilkS")
			(hide yes)
			(effects
				(font
					(size 1.27 1.27)
				)
			)
		)
		(property "Value" ""
			(at 0 0 180)
			(layer "F.Fab")
			(effects
				(font
					(size 1.27 1.27)
				)
			)
		)
		(duplicate_pad_numbers_are_jumpers no)
		(fp_line
			(start 0.7874 0.4064)
			(end -0.7874 0.4064)
			(stroke
				(width 0.1524)
				(type default)
			)
			(layer "F.SilkS")
		)
		(fp_line
			(start 0.7874 -0.4064)
			(end 0.7874 0.4064)
			(stroke
				(width 0.1524)
				(type default)
			)
			(layer "F.SilkS")
		)
		(fp_line
			(start -0.7874 0.4064)
			(end -0.7874 -0.4064)
			(stroke
				(width 0.1524)
				(type default)
			)
			(layer "F.SilkS")
		)
		(fp_line
			(start -0.7874 -0.4064)
			(end 0.7874 -0.4064)
			(stroke
				(width 0.1524)
				(type default)
			)
			(layer "F.SilkS")
		)
		(fp_line
			(start 0.67945 0.3048)
			(end 0.120396 0.3048)
			(stroke
				(width 0.1)
				(type default)
			)
			(layer "F.Fab")
		)
		(fp_line
			(start 0.67945 -0.3048)
			(end 0.67945 0.3048)
			(stroke
				(width 0.1)
				(type default)
			)
			(layer "F.Fab")
		)
		(fp_line
			(start 0.12065 -0.2794)
			(end 0.12065 -0.3048)
			(stroke
				(width 0.1)
				(type default)
			)
			(layer "F.Fab")
		)
		(fp_line
			(start 0.12065 -0.3048)
			(end 0.67945 -0.3048)
			(stroke
				(width 0.1)
				(type default)
			)
			(layer "F.Fab")
		)
		(fp_line
			(start 0.120396 0.3048)
			(end 0.120396 0.2794)
			(stroke
				(width 0.1)
				(type default)
			)
			(layer "F.Fab")
		)
		(fp_line
			(start 0.120396 0.2794)
			(end -0.12065 0.2794)
			(stroke
				(width 0.1)
				(type default)
			)
			(layer "F.Fab")
		)
		(fp_line
			(start -0.12065 0.3048)
			(end -0.67945 0.3048)
			(stroke
				(width 0.1)
				(type default)
			)
			(layer "F.Fab")
		)
		(fp_line
			(start -0.12065 0.2794)
			(end -0.12065 0.3048)
			(stroke
				(width 0.1)
				(type default)
			)
			(layer "F.Fab")
		)
		(fp_line
			(start -0.12065 -0.2794)
			(end 0.12065 -0.2794)
			(stroke
				(width 0.1)
				(type default)
			)
			(layer "F.Fab")
		)
		(fp_line
			(start -0.12065 -0.305054)
			(end -0.12065 -0.2794)
			(stroke
				(width 0.1)
				(type default)
			)
			(layer "F.Fab")
		)
		(fp_line
			(start -0.67945 0.3048)
			(end -0.67945 -0.305054)
			(stroke
				(width 0.1)
				(type default)
			)
			(layer "F.Fab")
		)
		(fp_line
			(start -0.67945 -0.305054)
			(end -0.12065 -0.305054)
			(stroke
				(width 0.1)
				(type default)
			)
			(layer "F.Fab")
		)
		(pad "1" smd circle
			(at -0.40005 0 180)
			(size 0 0)
			(layers "F.Cu" "F.Mask" "F.Paste")
			(net "SW_PVCCINFAON_CPU0_BOOT1_R")
		)
		(pad "2" smd circle
			(at 0.40005 0 180)
			(size 0 0)
			(layers "F.Cu" "F.Mask" "F.Paste")
			(net "SW_PVCCINFAON_CPU0_BOOTR1")
		)
	)
)
